# T6G (Grand Teton) — schematic netlist excerpt (pin names and nets, part order shuffled) for the footprints in the layout excerpt that follows; sources: Cadence DE-HDL packaged netlist, KiCad conversion of 04192023_DAF0TMB3IC0_F0TG_MB_C_brd_V02_OCP.brd

R1363  Q_RES  33 5% CHIP  pkg 0402LF  page 259 : A = PWRGD_P12V_MEM ; B = PWRGD_P12V_MEM_R
PR523  Q_RES  1.5 1% EMPTY  pkg 0402LF  page 212 : A = SW_PVDDCR_CPU0_P1_SW4_RC ; B = GND
R1016  Q_RES  20K 1% CHIP  pkg 0201LF  page 287 : A = RT_CPU0_P1_ADDR2 ; B = GND

(kicad_pcb
	(version 20260206)
	(generator "pcbnew")
	(generator_version "10.0")
	(general
		(thickness 1.6)
		(legacy_teardrops no)
	)
	(paper "A4")
	(title_block
		(title "04192023_DAF0TMB3IC0_F0TG_MB_C_brd_V02_OCP.brd")
		(comment 1 "Grand Teton / footprints 2704-2706 of 8354")
	)
	(layers
		(0 "F.Cu" signal "TOP")
		(4 "In1.Cu" signal "GND")
		(6 "In2.Cu" signal "IN1")
		(8 "In3.Cu" signal "GND1")
		(10 "In4.Cu" signal "IN2")
		(12 "In5.Cu" signal "GND2")
		(14 "In6.Cu" signal "IN3")
		(16 "In7.Cu" signal "GND3")
		(18 "In8.Cu" signal "VCC")
		(20 "In9.Cu" signal "VCC1")
		(22 "In10.Cu" signal "GND4")
		(24 "In11.Cu" signal "IN4")
		(26 "In12.Cu" signal "GND5")
		(28 "In13.Cu" signal "IN5")
		(30 "In14.Cu" signal "GND6")
		(32 "In15.Cu" signal "IN6")
		(34 "In16.Cu" signal "GND7")
		(2 "B.Cu" signal "BOTTOM")
		(9 "F.Adhes" user "F.Adhesive")
		(11 "B.Adhes" user "B.Adhesive")
		(13 "F.Paste" user "Package Geometry/Pastemask Top")
		(15 "B.Paste" user "Package Geometry/Pastemask Bottom")
		(5 "F.SilkS" user "Ref Des/Silkscreen Top")
		(7 "B.SilkS" user "Ref Des/Silkscreen Bottom")
		(1 "F.Mask" user "Board Geometry/Soldermask Top")
		(3 "B.Mask" user "Board Geometry/Soldermask Bottom")
		(17 "Dwgs.User" user "User.Drawings")
		(19 "Cmts.User" user "User.Comments")
		(21 "Eco1.User" user "User.Eco1")
		(23 "Eco2.User" user "User.Eco2")
		(25 "Edge.Cuts" user "Board Geometry/Outline")
		(27 "Margin" user)
		(31 "F.CrtYd" user "Package Geometry/Place Bound Top")
		(29 "B.CrtYd" user "Package Geometry/Place Bound Bottom")
		(35 "F.Fab" user "Ref Des/Assembly Top")
		(33 "B.Fab" user "Ref Des/Assembly Bottom")
	)
	(footprint ""
		(layer "F.Cu")
		(at 111.133128 -179.906168 -90)
		(property "Reference" "PR523"
			(at 0 0 270)
			(layer "F.SilkS")
			(hide yes)
			(effects
				(font
					(size 1.27 1.27)
				)
			)
		)
		(property "Value" ""
			(at 0 0 270)
			(layer "F.Fab")
			(effects
				(font
					(size 1.27 1.27)
				)
			)
		)
		(duplicate_pad_numbers_are_jumpers no)
		(fp_line
			(start -0.7874 0.4064)
			(end -0.7874 -0.4064)
			(stroke
				(width 0.1524)
				(type default)
			)
			(layer "F.SilkS")
		)
		(fp_line
			(start 0.7874 0.4064)
			(end -0.7874 0.4064)
			(stroke
				(width 0.1524)
				(type default)
			)
			(layer "F.SilkS")
		)
		(fp_line
			(start -0.7874 -0.4064)
			(end 0.7874 -0.4064)
			(stroke
				(width 0.1524)
				(type default)
			)
			(layer "F.SilkS")
		)
		(fp_line
			(start 0.7874 -0.4064)
			(end 0.7874 0.4064)
			(stroke
				(width 0.1524)
				(type default)
			)
			(layer "F.SilkS")
		)
		(fp_line
			(start -0.67945 0.3048)
			(end -0.67945 -0.305054)
			(stroke
				(width 0.1)
				(type default)
			)
			(layer "F.Fab")
		)
		(fp_line
			(start -0.12065 0.3048)
			(end -0.67945 0.3048)
			(stroke
				(width 0.1)
				(type default)
			)
			(layer "F.Fab")
		)
		(fp_line
			(start 0.120396 0.3048)
			(end 0.120396 0.2794)
			(stroke
				(width 0.1)
				(type default)
			)
			(layer "F.Fab")
		)
		(fp_line
			(start 0.67945 0.3048)
			(end 0.120396 0.3048)
			(stroke
				(width 0.1)
				(type default)
			)
			(layer "F.Fab")
		)
		(fp_line
			(start -0.12065 0.2794)
			(end -0.12065 0.3048)
			(stroke
				(width 0.1)
				(type default)
			)
			(layer "F.Fab")
		)
		(fp_line
			(start 0.120396 0.2794)
			(end -0.12065 0.2794)
			(stroke
				(width 0.1)
				(type default)
			)
			(layer "F.Fab")
		)
		(fp_line
			(start -0.12065 -0.2794)
			(end 0.12065 -0.2794)
			(stroke
				(width 0.1)
				(type default)
			)
			(layer "F.Fab")
		)
		(fp_line
			(start 0.12065 -0.2794)
			(end 0.12065 -0.3048)
			(stroke
				(width 0.1)
				(type default)
			)
			(layer "F.Fab")
		)
		(fp_line
			(start 0.12065 -0.3048)
			(end 0.67945 -0.3048)
			(stroke
				(width 0.1)
				(type default)
			)
			(layer "F.Fab")
		)
		(fp_line
			(start 0.67945 -0.3048)
			(end 0.67945 0.3048)
			(stroke
				(width 0.1)
				(type default)
			)
			(layer "F.Fab")
		)
		(fp_line
			(start -0.67945 -0.305054)
			(end -0.12065 -0.305054)
			(stroke
				(width 0.1)
				(type default)
			)
			(layer "F.Fab")
		)
		(fp_line
			(start -0.12065 -0.305054)
			(end -0.12065 -0.2794)
			(stroke
				(width 0.1)
				(type default)
			)
			(layer "F.Fab")
		)
		(pad "1" smd circle
			(at -0.40005 0 270)
			(size 0 0)
			(layers "F.Cu" "F.Mask" "F.Paste")
			(net "SW_PVDDCR_CPU0_P1_SW4_RC")
		)
		(pad "2" smd circle
			(at 0.40005 0 270)
			(size 0 0)
			(layers "F.Cu" "F.Mask" "F.Paste")
			(net "GND")
		)
	)
	(footprint ""
		(layer "F.Cu")
		(at 361.22229 -395.1732 90)
		(property "Reference" "R1016"
			(at 0 0 90)
			(layer "F.SilkS")
			(hide yes)
			(effects
				(font
					(size 1.27 1.27)
				)
			)
		)
		(property "Value" ""
			(at 0 0 90)
			(layer "F.Fab")
			(effects
				(font
					(size 1.27 1.27)
				)
			)
		)
		(duplicate_pad_numbers_are_jumpers no)
		(fp_line
			(start 0.32512 -0.175006)
			(end 0.32512 0.175006)
			(stroke
				(width 0.1)
				(type default)
			)
			(layer "F.Fab")
		)
		(fp_line
			(start -0.32512 -0.175006)
			(end 0.32512 -0.175006)
			(stroke
				(width 0.1)
				(type default)
			)
			(layer "F.Fab")
		)
		(fp_line
			(start 0.32512 0.175006)
			(end -0.32512 0.175006)
			(stroke
				(width 0.1)
				(type default)
			)
			(layer "F.Fab")
		)
		(fp_line
			(start -0.32512 0.175006)
			(end -0.32512 -0.175006)
			(stroke
				(width 0.1)
				(type default)
			)
			(layer "F.Fab")
		)
		(pad "1" smd rect
			(at -0.2667 0 90)
			(size 0.3048 0.381)
			(layers "F.Cu" "F.Mask" "F.Paste")
			(net "RT_CPU0_P1_ADDR2")
		)
		(pad "2" smd rect
			(at 0.2667 0 270)
			(size 0.3048 0.381)
			(layers "F.Cu" "F.Mask" "F.Paste")
			(net "GND")
		)
	)
	(footprint ""
		(layer "F.Cu")
		(at 96.058736 -119.469154 -90)
		(property "Reference" "R1363"
			(at 0 0 270)
			(layer "F.SilkS")
			(hide yes)
			(effects
				(font
					(size 1.27 1.27)
				)
			)
		)
		(property "Value" ""
			(at 0 0 270)
			(layer "F.Fab")
			(effects
				(font
					(size 1.27 1.27)
				)
			)
		)
		(duplicate_pad_numbers_are_jumpers no)
		(fp_line
			(start -0.7874 0.4064)
			(end -0.7874 -0.4064)
			(stroke
				(width 0.1524)
				(type default)
			)
			(layer "F.SilkS")
		)
		(fp_line
			(start 0.7874 0.4064)
			(end -0.7874 0.4064)
			(stroke
				(width 0.1524)
				(type default)
			)
			(layer "F.SilkS")
		)
		(fp_line
			(start -0.7874 -0.4064)
			(end 0.7874 -0.4064)
			(stroke
				(width 0.1524)
				(type default)
			)
			(layer "F.SilkS")
		)
		(fp_line
			(start 0.7874 -0.4064)
			(end 0.7874 0.4064)
			(stroke
				(width 0.1524)
				(type default)
			)
			(layer "F.SilkS")
		)
		(fp_line
			(start -0.67945 0.3048)
			(end -0.67945 -0.305054)
			(stroke
				(width 0.1)
				(type default)
			)
			(layer "F.Fab")
		)
		(fp_line
			(start -0.12065 0.3048)
			(end -0.67945 0.3048)
			(stroke
				(width 0.1)
				(type default)
			)
			(layer "F.Fab")
		)
		(fp_line
			(start 0.120396 0.3048)
			(end 0.120396 0.2794)
			(stroke
				(width 0.1)
				(type default)
			)
			(layer "F.Fab")
		)
		(fp_line
			(start 0.67945 0.3048)
			(end 0.120396 0.3048)
			(stroke
				(width 0.1)
				(type default)
			)
			(layer "F.Fab")
		)
		(fp_line
			(start -0.12065 0.2794)
			(end -0.12065 0.3048)
			(stroke
				(width 0.1)
				(type default)
			)
			(layer "F.Fab")
		)
		(fp_line
			(start 0.120396 0.2794)
			(end -0.12065 0.2794)
			(stroke
				(width 0.1)
				(type default)
			)
			(layer "F.Fab")
		)
		(fp_line
			(start -0.12065 -0.2794)
			(end 0.12065 -0.2794)
			(stroke
				(width 0.1)
				(type default)
			)
			(layer "F.Fab")
		)
		(fp_line
			(start 0.12065 -0.2794)
			(end 0.12065 -0.3048)
			(stroke
				(width 0.1)
				(type default)
			)
			(layer "F.Fab")
		)
		(fp_line
			(start 0.12065 -0.3048)
			(end 0.67945 -0.3048)
			(stroke
				(width 0.1)
				(type default)
			)
			(layer "F.Fab")
		)
		(fp_line
			(start 0.67945 -0.3048)
			(end 0.67945 0.3048)
			(stroke
				(width 0.1)
				(type default)
			)
			(layer "F.Fab")
		)
		(fp_line
			(start -0.67945 -0.305054)
			(end -0.12065 -0.305054)
			(stroke
				(width 0.1)
				(type default)
			)
			(layer "F.Fab")
		)
		(fp_line
			(start -0.12065 -0.305054)
			(end -0.12065 -0.2794)
			(stroke
				(width 0.1)
				(type default)
			)
			(layer "F.Fab")
		)
		(pad "1" smd circle
			(at -0.40005 0 270)
			(size 0 0)
			(layers "F.Cu" "F.Mask" "F.Paste")
			(net "PWRGD_P12V_MEM")
		)
		(pad "2" smd circle
			(at 0.40005 0 270)
			(size 0 0)
			(layers "F.Cu" "F.Mask" "F.Paste")
			(net "PWRGD_P12V_MEM_R")
		)
	)
)
